(kicad_pcb
	(version 20241229)
	(generator "pcbnew")
	(generator_version "9.0")
	(general
		(thickness 1.292)
		(legacy_teardrops no)
	)
	(paper "A4")
	(title_block
		(title "LPDDR5 Testbed")
		(date "2023-12-19")
		(rev "1.0.0")
		(comment 9 "footprints 83-88 of 160")
	)
	(layers
		(0 "F.Cu" signal)
		(4 "In1.Cu" power)
		(6 "In2.Cu" power)
		(8 "In3.Cu" signal)
		(10 "In4.Cu" signal)
		(2 "B.Cu" signal)
		(9 "F.Adhes" user "F.Adhesive")
		(11 "B.Adhes" user "B.Adhesive")
		(13 "F.Paste" user)
		(15 "B.Paste" user)
		(5 "F.SilkS" user "F.Silkscreen")
		(7 "B.SilkS" user "B.Silkscreen")
		(1 "F.Mask" user)
		(3 "B.Mask" user)
		(17 "Dwgs.User" user "User.Drawings")
		(19 "Cmts.User" user "User.Comments")
		(21 "Eco1.User" user "User.Eco1")
		(23 "Eco2.User" user "User.Eco2")
		(25 "Edge.Cuts" user)
		(27 "Margin" user)
		(31 "F.CrtYd" user "F.Courtyard")
		(29 "B.CrtYd" user "B.Courtyard")
		(35 "F.Fab" user)
		(33 "B.Fab" user)
	)
	(footprint "antmicro-footprints:R_0402_1005Metric"
		(layer "B.Cu")
		(at 115.68 92.02 180)
		(descr "Resistor SMD 0402")
		(tags "resistor SMD 0402")
		(property "Reference" "R94"
			(at 1.08 -0.38 0)
			(unlocked yes)
			(layer "B.SilkS")
			(effects
				(font
					(size 0.7 0.7)
					(thickness 0.15)
				)
				(justify left bottom mirror)
			)
		)
		(property "Value" "R_100R_0402"
			(at -1.011843 -1.772047 0)
			(layer "B.Fab")
			(effects
				(font
					(size 0.7 0.7)
					(thickness 0.15)
				)
				(justify left bottom mirror)
			)
		)
		(property "Author" "Antmicro"
			(at 231.36 184.04 0)
			(layer "B.Fab")
			(hide yes)
			(effects
				(font
					(size 1 1)
					(thickness 0.15)
				)
				(justify mirror)
			)
		)
		(property "License" "Apache-2.0"
			(at 231.36 184.04 0)
			(layer "B.Fab")
			(hide yes)
			(effects
				(font
					(size 1 1)
					(thickness 0.15)
				)
				(justify mirror)
			)
		)
		(property "MPN" "CR0402-FX-1000GLF"
			(at 231.36 184.04 0)
			(layer "B.Fab")
			(hide yes)
			(effects
				(font
					(size 1 1)
					(thickness 0.15)
				)
				(justify mirror)
			)
		)
		(property "Manufacturer" "Bourns"
			(at 231.36 184.04 0)
			(layer "B.Fab")
			(hide yes)
			(effects
				(font
					(size 1 1)
					(thickness 0.15)
				)
				(justify mirror)
			)
		)
		(property "Tolerance" "1%"
			(at 231.36 184.04 0)
			(layer "B.Fab")
			(hide yes)
			(effects
				(font
					(size 1 1)
					(thickness 0.15)
				)
				(justify mirror)
			)
		)
		(property "Val" "100R"
			(at 231.36 184.04 0)
			(layer "B.Fab")
			(hide yes)
			(effects
				(font
					(size 1 1)
					(thickness 0.15)
				)
				(justify mirror)
			)
		)
		(sheetname "Translators")
		(sheetfile "translators.kicad_sch")
		(attr smd)
		(fp_rect
			(start -0.93 0.47)
			(end 0.93 -0.47)
			(stroke
				(width 0.05)
				(type solid)
			)
			(fill no)
			(layer "B.CrtYd")
		)
		(fp_rect
			(start -0.5 0.25)
			(end 0.5 -0.25)
			(stroke
				(width 0.15)
				(type solid)
			)
			(fill no)
			(layer "B.Fab")
		)
		(pad "1" smd roundrect
			(at -0.485 0 180)
			(size 0.59 0.64)
			(layers "B.Cu" "B.Mask" "B.Paste")
			(roundrect_rratio 0.25)
			(net 201 "/LPDDR5/LPDDR5_A.DMI0")
			(pintype "passive")
		)
		(pad "2" smd roundrect
			(at 0.485 0 180)
			(size 0.59 0.64)
			(layers "B.Cu" "B.Mask" "B.Paste")
			(roundrect_rratio 0.25)
			(net 14 "GND")
			(pintype "passive")
		)
	)
	(footprint "antmicro-footprints:R_Array_4x0402_Panasonic_EXB28V"
		(layer "B.Cu")
		(at 130.3 93.8)
		(property "Reference" "R22"
			(at 1.1 -1.3 0)
			(unlocked yes)
			(layer "B.SilkS")
			(effects
				(font
					(size 0.7 0.7)
					(thickness 0.15)
				)
				(justify left bottom mirror)
			)
		)
		(property "Value" "R_4x100R_0402_array"
			(at -1.5 -2 180)
			(layer "B.Fab")
			(effects
				(font
					(size 0.7 0.7)
					(thickness 0.15)
				)
				(justify left bottom mirror)
			)
		)
		(property "Author" "Antmicro"
			(at 0 0 0)
			(layer "B.Fab")
			(hide yes)
			(effects
				(font
					(size 1 1)
					(thickness 0.15)
				)
				(justify mirror)
			)
		)
		(property "License" "Apache-2.0"
			(at 0 0 0)
			(layer "B.Fab")
			(hide yes)
			(effects
				(font
					(size 1 1)
					(thickness 0.15)
				)
				(justify mirror)
			)
		)
		(property "MPN" "EXB-28V101JX"
			(at 0 0 0)
			(layer "B.Fab")
			(hide yes)
			(effects
				(font
					(size 1 1)
					(thickness 0.15)
				)
				(justify mirror)
			)
		)
		(property "Manufacturer" "Panasonic"
			(at 0 0 0)
			(layer "B.Fab")
			(hide yes)
			(effects
				(font
					(size 1 1)
					(thickness 0.15)
				)
				(justify mirror)
			)
		)
		(property "Val" "R_4x100R_0402"
			(at 0 0 0)
			(layer "B.Fab")
			(hide yes)
			(effects
				(font
					(size 1 1)
					(thickness 0.15)
				)
				(justify mirror)
			)
		)
		(sheetname "Translators")
		(sheetfile "translators.kicad_sch")
		(attr smd)
		(fp_line
			(start -1.25 0.5)
			(end -1.25 -0.498)
			(stroke
				(width 0.15)
				(type solid)
			)
			(layer "B.SilkS")
		)
		(fp_line
			(start 1.25 -0.499)
			(end 1.25 0.499)
			(stroke
				(width 0.15)
				(type solid)
			)
			(layer "B.SilkS")
		)
		(fp_rect
			(start -1.25 0.8)
			(end 1.25 -0.8)
			(stroke
				(width 0.05)
				(type solid)
			)
			(fill no)
			(layer "B.CrtYd")
		)
		(fp_line
			(start -1 -0.498)
			(end -1 0.5)
			(stroke
				(width 0.15)
				(type solid)
			)
			(layer "B.Fab")
		)
		(fp_line
			(start -1 0.5)
			(end 0.998 0.5)
			(stroke
				(width 0.15)
				(type solid)
			)
			(layer "B.Fab")
		)
		(fp_line
			(start 0.998 -0.498)
			(end -1 -0.498)
			(stroke
				(width 0.15)
				(type solid)
			)
			(layer "B.Fab")
		)
		(fp_line
			(start 0.998 0.5)
			(end 0.998 -0.498)
			(stroke
				(width 0.15)
				(type solid)
			)
			(layer "B.Fab")
		)
		(pad "1" smd roundrect
			(at -0.8875 -0.45)
			(size 0.525 0.5)
			(layers "B.Cu" "B.Mask" "B.Paste")
			(roundrect_rratio 0.25)
			(net 59 "/LPDDR5/LPDDR5_A.CA2")
			(pinfunction "R1.1")
			(pintype "passive")
		)
		(pad "2" smd roundrect
			(at -0.25 -0.45)
			(size 0.25 0.5)
			(layers "B.Cu" "B.Mask" "B.Paste")
			(roundrect_rratio 0.25)
			(net 54 "/LPDDR5/LPDDR5_A.CA3")
			(pinfunction "R2.1")
			(pintype "passive")
		)
		(pad "3" smd roundrect
			(at 0.25 -0.45)
			(size 0.25 0.5)
			(layers "B.Cu" "B.Mask" "B.Paste")
			(roundrect_rratio 0.25)
			(net 60 "/LPDDR5/LPDDR5_A.CA4")
			(pinfunction "R3.1")
			(pintype "passive")
		)
		(pad "4" smd roundrect
			(at 0.8875 -0.45)
			(size 0.525 0.5)
			(layers "B.Cu" "B.Mask" "B.Paste")
			(roundrect_rratio 0.25)
			(net 56 "/LPDDR5/LPDDR5_A.CA5")
			(pinfunction "R4.1")
			(pintype "passive")
		)
		(pad "5" smd roundrect
			(at 0.8875 0.45)
			(size 0.525 0.5)
			(layers "B.Cu" "B.Mask" "B.Paste")
			(roundrect_rratio 0.25)
			(net 14 "GND")
			(pinfunction "R4.2")
			(pintype "passive")
		)
		(pad "6" smd roundrect
			(at 0.25 0.45)
			(size 0.25 0.5)
			(layers "B.Cu" "B.Mask" "B.Paste")
			(roundrect_rratio 0.25)
			(net 14 "GND")
			(pinfunction "R3.2")
			(pintype "passive")
		)
		(pad "7" smd roundrect
			(at -0.25 0.45)
			(size 0.25 0.5)
			(layers "B.Cu" "B.Mask" "B.Paste")
			(roundrect_rratio 0.25)
			(net 14 "GND")
			(pinfunction "R2.2")
			(pintype "passive")
		)
		(pad "8" smd roundrect
			(at -0.8875 0.45)
			(size 0.525 0.5)
			(layers "B.Cu" "B.Mask" "B.Paste")
			(roundrect_rratio 0.25)
			(net 14 "GND")
			(pinfunction "R1.2")
			(pintype "passive")
		)
	)
	(footprint "antmicro-footprints:C_0402_1005Metric"
		(layer "B.Cu")
		(at 138.775 81.45 180)
		(descr "Capacitor SMD 0402")
		(tags "capacitor SMD 0402")
		(property "Reference" "C69"
			(at -1.125 0.55 0)
			(unlocked yes)
			(layer "B.SilkS")
			(effects
				(font
					(size 0.7 0.7)
					(thickness 0.15)
				)
				(justify left bottom mirror)
			)
		)
		(property "Value" "C_4u7_0402"
			(at -1.022927 -2.155213 0)
			(layer "B.Fab")
			(effects
				(font
					(size 0.7 0.7)
					(thickness 0.15)
				)
				(justify left bottom mirror)
			)
		)
		(property "Author" "Antmicro"
			(at 277.55 162.9 0)
			(layer "B.Fab")
			(hide yes)
			(effects
				(font
					(size 1 1)
					(thickness 0.15)
				)
				(justify mirror)
			)
		)
		(property "Dielectric" ""
			(at 277.55 162.9 0)
			(layer "B.Fab")
			(hide yes)
			(effects
				(font
					(size 1 1)
					(thickness 0.15)
				)
				(justify mirror)
			)
		)
		(property "License" "Apache-2.0"
			(at 277.55 162.9 0)
			(layer "B.Fab")
			(hide yes)
			(effects
				(font
					(size 1 1)
					(thickness 0.15)
				)
				(justify mirror)
			)
		)
		(property "MPN" "GRM155R61A475MEAAD"
			(at 277.55 162.9 0)
			(layer "B.Fab")
			(hide yes)
			(effects
				(font
					(size 1 1)
					(thickness 0.15)
				)
				(justify mirror)
			)
		)
		(property "Manufacturer" "Murata"
			(at 277.55 162.9 0)
			(layer "B.Fab")
			(hide yes)
			(effects
				(font
					(size 1 1)
					(thickness 0.15)
				)
				(justify mirror)
			)
		)
		(property "Val" "4u7"
			(at 277.55 162.9 0)
			(layer "B.Fab")
			(hide yes)
			(effects
				(font
					(size 1 1)
					(thickness 0.15)
				)
				(justify mirror)
			)
		)
		(property "Voltage" ""
			(at 277.55 162.9 0)
			(layer "B.Fab")
			(hide yes)
			(effects
				(font
					(size 1 1)
					(thickness 0.15)
				)
				(justify mirror)
			)
		)
		(sheetname "LPDDR5")
		(sheetfile "lpddr5.kicad_sch")
		(attr smd)
		(fp_rect
			(start -0.9659 0.481258)
			(end 0.9649 -0.458742)
			(stroke
				(width 0.05)
				(type solid)
			)
			(fill no)
			(layer "B.CrtYd")
		)
		(fp_line
			(start 0.499 0.25)
			(end 0.499 -0.248)
			(stroke
				(width 0.15)
				(type solid)
			)
			(layer "B.Fab")
		)
		(fp_line
			(start 0.499 -0.248)
			(end -0.499 -0.248)
			(stroke
				(width 0.15)
				(type solid)
			)
			(layer "B.Fab")
		)
		(fp_line
			(start -0.499 0.25)
			(end 0.499 0.25)
			(stroke
				(width 0.15)
				(type solid)
			)
			(layer "B.Fab")
		)
		(fp_line
			(start -0.499 -0.248)
			(end -0.499 0.25)
			(stroke
				(width 0.15)
				(type solid)
			)
			(layer "B.Fab")
		)
		(pad "1" smd roundrect
			(at -0.484 0 180)
			(size 0.59 0.64)
			(layers "B.Cu" "B.Mask" "B.Paste")
			(roundrect_rratio 0.25)
			(net 14 "GND")
			(pintype "passive")
		)
		(pad "2" smd roundrect
			(at 0.484 0 180)
			(size 0.59 0.64)
			(layers "B.Cu" "B.Mask" "B.Paste")
			(roundrect_rratio 0.25)
			(net 13 "+1V05")
			(pintype "passive")
		)
	)
	(footprint "antmicro-footprints:R_0402_1005Metric"
		(layer "B.Cu")
		(at 106.63 90.97 90)
		(descr "Resistor SMD 0402")
		(tags "resistor SMD 0402")
		(property "Reference" "R13"
			(at -0.13 -2.63 0)
			(unlocked yes)
			(layer "B.SilkS")
			(effects
				(font
					(size 0.7 0.7)
					(thickness 0.15)
				)
				(justify right bottom mirror)
			)
		)
		(property "Value" "R_100R_0402"
			(at -1.011843 -1.772047 90)
			(layer "B.Fab")
			(effects
				(font
					(size 0.7 0.7)
					(thickness 0.15)
				)
				(justify right bottom mirror)
			)
		)
		(property "Author" "Antmicro"
			(at 197.6 -15.66 0)
			(layer "B.Fab")
			(hide yes)
			(effects
				(font
					(size 1 1)
					(thickness 0.15)
				)
				(justify mirror)
			)
		)
		(property "License" "Apache-2.0"
			(at 197.6 -15.66 0)
			(layer "B.Fab")
			(hide yes)
			(effects
				(font
					(size 1 1)
					(thickness 0.15)
				)
				(justify mirror)
			)
		)
		(property "MPN" "CR0402-FX-1000GLF"
			(at 197.6 -15.66 0)
			(layer "B.Fab")
			(hide yes)
			(effects
				(font
					(size 1 1)
					(thickness 0.15)
				)
				(justify mirror)
			)
		)
		(property "Manufacturer" "Bourns"
			(at 197.6 -15.66 0)
			(layer "B.Fab")
			(hide yes)
			(effects
				(font
					(size 1 1)
					(thickness 0.15)
				)
				(justify mirror)
			)
		)
		(property "Tolerance" "1%"
			(at 197.6 -15.66 0)
			(layer "B.Fab")
			(hide yes)
			(effects
				(font
					(size 1 1)
					(thickness 0.15)
				)
				(justify mirror)
			)
		)
		(property "Val" "100R"
			(at 197.6 -15.66 0)
			(layer "B.Fab")
			(hide yes)
			(effects
				(font
					(size 1 1)
					(thickness 0.15)
				)
				(justify mirror)
			)
		)
		(sheetname "Translators")
		(sheetfile "translators.kicad_sch")
		(attr smd)
		(fp_rect
			(start -0.93 0.47)
			(end 0.93 -0.47)
			(stroke
				(width 0.05)
				(type solid)
			)
			(fill no)
			(layer "B.CrtYd")
		)
		(fp_rect
			(start -0.5 0.25)
			(end 0.5 -0.25)
			(stroke
				(width 0.15)
				(type solid)
			)
			(fill no)
			(layer "B.Fab")
		)
		(pad "1" smd roundrect
			(at -0.485 0 90)
			(size 0.59 0.64)
			(layers "B.Cu" "B.Mask" "B.Paste")
			(roundrect_rratio 0.25)
			(net 182 "/SODIMM/LPDDR5_IN_A.WCK1_N")
			(pintype "passive")
		)
		(pad "2" smd roundrect
			(at 0.485 0 90)
			(size 0.59 0.64)
			(layers "B.Cu" "B.Mask" "B.Paste")
			(roundrect_rratio 0.25)
			(net 47 "/LPDDR5/LPDDR5_A.WCK1_N")
			(pintype "passive")
		)
	)
	(footprint "antmicro-footprints:C_0402_1005Metric"
		(layer "B.Cu")
		(at 140.375 84.95)
		(descr "Capacitor SMD 0402")
		(tags "capacitor SMD 0402")
		(property "Reference" "C43"
			(at 0.925 0.55 0)
			(unlocked yes)
			(layer "B.SilkS")
			(effects
				(font
					(size 0.7 0.7)
					(thickness 0.15)
				)
				(justify right bottom mirror)
			)
		)
		(property "Value" "C_4u7_0402"
			(at -1.022927 -2.155213 0)
			(layer "B.Fab")
			(effects
				(font
					(size 0.7 0.7)
					(thickness 0.15)
				)
				(justify right bottom mirror)
			)
		)
		(property "Author" "Antmicro"
			(at 0 0 0)
			(layer "B.Fab")
			(hide yes)
			(effects
				(font
					(size 1 1)
					(thickness 0.15)
				)
				(justify mirror)
			)
		)
		(property "Dielectric" ""
			(at 0 0 0)
			(layer "B.Fab")
			(hide yes)
			(effects
				(font
					(size 1 1)
					(thickness 0.15)
				)
				(justify mirror)
			)
		)
		(property "License" "Apache-2.0"
			(at 0 0 0)
			(layer "B.Fab")
			(hide yes)
			(effects
				(font
					(size 1 1)
					(thickness 0.15)
				)
				(justify mirror)
			)
		)
		(property "MPN" "GRM155R61A475MEAAD"
			(at 0 0 0)
			(layer "B.Fab")
			(hide yes)
			(effects
				(font
					(size 1 1)
					(thickness 0.15)
				)
				(justify mirror)
			)
		)
		(property "Manufacturer" "Murata"
			(at 0 0 0)
			(layer "B.Fab")
			(hide yes)
			(effects
				(font
					(size 1 1)
					(thickness 0.15)
				)
				(justify mirror)
			)
		)
		(property "Val" "4u7"
			(at 0 0 0)
			(layer "B.Fab")
			(hide yes)
			(effects
				(font
					(size 1 1)
					(thickness 0.15)
				)
				(justify mirror)
			)
		)
		(property "Voltage" ""
			(at 0 0 0)
			(layer "B.Fab")
			(hide yes)
			(effects
				(font
					(size 1 1)
					(thickness 0.15)
				)
				(justify mirror)
			)
		)
		(sheetname "LPDDR5")
		(sheetfile "lpddr5.kicad_sch")
		(attr smd)
		(fp_rect
			(start -0.9659 0.481258)
			(end 0.9649 -0.458742)
			(stroke
				(width 0.05)
				(type solid)
			)
			(fill no)
			(layer "B.CrtYd")
		)
		(fp_line
			(start -0.499 -0.248)
			(end -0.499 0.25)
			(stroke
				(width 0.15)
				(type solid)
			)
			(layer "B.Fab")
		)
		(fp_line
			(start -0.499 0.25)
			(end 0.499 0.25)
			(stroke
				(width 0.15)
				(type solid)
			)
			(layer "B.Fab")
		)
		(fp_line
			(start 0.499 -0.248)
			(end -0.499 -0.248)
			(stroke
				(width 0.15)
				(type solid)
			)
			(layer "B.Fab")
		)
		(fp_line
			(start 0.499 0.25)
			(end 0.499 -0.248)
			(stroke
				(width 0.15)
				(type solid)
			)
			(layer "B.Fab")
		)
		(pad "1" smd roundrect
			(at -0.484 0)
			(size 0.59 0.64)
			(layers "B.Cu" "B.Mask" "B.Paste")
			(roundrect_rratio 0.25)
			(net 14 "GND")
			(pintype "passive")
		)
		(pad "2" smd roundrect
			(at 0.484 0)
			(size 0.59 0.64)
			(layers "B.Cu" "B.Mask" "B.Paste")
			(roundrect_rratio 0.25)
			(net 4 "+0V5")
			(pintype "passive")
		)
	)
	(footprint "antmicro-footprints:R_0402_1005Metric"
		(layer "B.Cu")
		(at 154.9 89.31)
		(descr "Resistor SMD 0402")
		(tags "resistor SMD 0402")
		(property "Reference" "R82"
			(at -1 -0.61 0)
			(unlocked yes)
			(layer "B.SilkS")
			(effects
				(font
					(size 0.7 0.7)
					(thickness 0.15)
				)
				(justify right bottom mirror)
			)
		)
		(property "Value" "R_100R_0402"
			(at -1.011843 -1.772047 0)
			(layer "B.Fab")
			(effects
				(font
					(size 0.7 0.7)
					(thickness 0.15)
				)
				(justify right bottom mirror)
			)
		)
		(property "Author" "Antmicro"
			(at 0 0 0)
			(layer "B.Fab")
			(hide yes)
			(effects
				(font
					(size 1 1)
					(thickness 0.15)
				)
				(justify mirror)
			)
		)
		(property "License" "Apache-2.0"
			(at 0 0 0)
			(layer "B.Fab")
			(hide yes)
			(effects
				(font
					(size 1 1)
					(thickness 0.15)
				)
				(justify mirror)
			)
		)
		(property "MPN" "CR0402-FX-1000GLF"
			(at 0 0 0)
			(layer "B.Fab")
			(hide yes)
			(effects
				(font
					(size 1 1)
					(thickness 0.15)
				)
				(justify mirror)
			)
		)
		(property "Manufacturer" "Bourns"
			(at 0 0 0)
			(layer "B.Fab")
			(hide yes)
			(effects
				(font
					(size 1 1)
					(thickness 0.15)
				)
				(justify mirror)
			)
		)
		(property "Tolerance" "1%"
			(at 0 0 0)
			(layer "B.Fab")
			(hide yes)
			(effects
				(font
					(size 1 1)
					(thickness 0.15)
				)
				(justify mirror)
			)
		)
		(property "Val" "100R"
			(at 0 0 0)
			(layer "B.Fab")
			(hide yes)
			(effects
				(font
					(size 1 1)
					(thickness 0.15)
				)
				(justify mirror)
			)
		)
		(sheetname "Translators1")
		(sheetfile "translators.kicad_sch")
		(attr smd)
		(fp_rect
			(start -0.93 0.47)
			(end 0.93 -0.47)
			(stroke
				(width 0.05)
				(type solid)
			)
			(fill no)
			(layer "B.CrtYd")
		)
		(fp_rect
			(start -0.5 0.25)
			(end 0.5 -0.25)
			(stroke
				(width 0.15)
				(type solid)
			)
			(fill no)
			(layer "B.Fab")
		)
		(pad "1" smd roundrect
			(at -0.485 0)
			(size 0.59 0.64)
			(layers "B.Cu" "B.Mask" "B.Paste")
			(roundrect_rratio 0.25)
			(net 111 "/LPDDR5/LPDDR5_B.WCK1_P")
			(pintype "passive")
		)
		(pad "2" smd roundrect
			(at 0.485 0)
			(size 0.59 0.64)
			(layers "B.Cu" "B.Mask" "B.Paste")
			(roundrect_rratio 0.25)
			(net 14 "GND")
			(pintype "passive")
		)
	)
)
